# S9S_MB_2U (Grand Teton) — schematic netlist excerpt (pin names and nets, part order shuffled) for the footprints in the layout excerpt that follows; sources: Cadence DE-HDL packaged netlist, KiCad conversion of 03242023_DA0F0TMBIJ0_F0T_Motherboard_J_brd_V01_OCP.brd

R898  Q_RES  33.2 1% CHIP  pkg 0402LF  page 114 : A = PWRGD_CHC_CPU1_DIMM2 ; B = PWRGD_FAIL_CPU1_CD
PC1940  Q_CAPP  330UF 2V 35% SPCAP  pkg SMLF  page 297 : A = PVCCD_HV_CPU1 ; B = GND

(kicad_pcb
	(version 20260206)
	(generator "pcbnew")
	(generator_version "10.0")
	(general
		(thickness 1.6)
		(legacy_teardrops no)
	)
	(paper "A4")
	(title_block
		(title "03242023_DA0F0TMBIJ0_F0T_Motherboard_J_brd_V01_OCP.brd")
		(comment 1 "Grand Teton / footprints 5013-5014 of 6105")
	)
	(layers
		(0 "F.Cu" signal "TOP")
		(4 "In1.Cu" signal "GND")
		(6 "In2.Cu" signal "IN1")
		(8 "In3.Cu" signal "GND1")
		(10 "In4.Cu" signal "IN2")
		(12 "In5.Cu" signal "GND2")
		(14 "In6.Cu" signal "IN3")
		(16 "In7.Cu" signal "GND3")
		(18 "In8.Cu" signal "VCC")
		(20 "In9.Cu" signal "VCC1")
		(22 "In10.Cu" signal "GND4")
		(24 "In11.Cu" signal "IN4")
		(26 "In12.Cu" signal "GND5")
		(28 "In13.Cu" signal "IN5")
		(30 "In14.Cu" signal "GND6")
		(32 "In15.Cu" signal "IN6")
		(34 "In16.Cu" signal "GND7")
		(2 "B.Cu" signal "BOTTOM")
		(9 "F.Adhes" user "F.Adhesive")
		(11 "B.Adhes" user "B.Adhesive")
		(13 "F.Paste" user "Package Geometry/Pastemask Top")
		(15 "B.Paste" user "Package Geometry/Pastemask Bottom")
		(5 "F.SilkS" user "Ref Des/Silkscreen Top")
		(7 "B.SilkS" user "Ref Des/Silkscreen Bottom")
		(1 "F.Mask" user "Board Geometry/Soldermask Top")
		(3 "B.Mask" user "Board Geometry/Soldermask Bottom")
		(17 "Dwgs.User" user "User.Drawings")
		(19 "Cmts.User" user "User.Comments")
		(21 "Eco1.User" user "User.Eco1")
		(23 "Eco2.User" user "User.Eco2")
		(25 "Edge.Cuts" user "Board Geometry/Outline")
		(27 "Margin" user)
		(31 "F.CrtYd" user "Package Geometry/Place Bound Top")
		(29 "B.CrtYd" user "Package Geometry/Place Bound Bottom")
		(35 "F.Fab" user "Ref Des/Assembly Top")
		(33 "B.Fab" user "Ref Des/Assembly Bottom")
	)
	(footprint ""
		(layer "B.Cu")
		(at 34.5313 -319.060068 90)
		(property "Reference" "R898"
			(at 0 0 90)
			(layer "B.SilkS")
			(hide yes)
			(effects
				(font
					(size 1.27 1.27)
				)
				(justify mirror)
			)
		)
		(property "Value" ""
			(at 0 0 90)
			(layer "B.Fab")
			(effects
				(font
					(size 1.27 1.27)
				)
				(justify mirror)
			)
		)
		(duplicate_pad_numbers_are_jumpers no)
		(fp_line
			(start 0.7874 -0.4064)
			(end -0.7874 -0.4064)
			(stroke
				(width 0.1524)
				(type default)
			)
			(layer "B.SilkS")
		)
		(fp_line
			(start -0.7874 -0.4064)
			(end -0.7874 0.4064)
			(stroke
				(width 0.1524)
				(type default)
			)
			(layer "B.SilkS")
		)
		(fp_line
			(start 0.7874 0.4064)
			(end 0.7874 -0.4064)
			(stroke
				(width 0.1524)
				(type default)
			)
			(layer "B.SilkS")
		)
		(fp_line
			(start -0.7874 0.4064)
			(end 0.7874 0.4064)
			(stroke
				(width 0.1524)
				(type default)
			)
			(layer "B.SilkS")
		)
		(fp_line
			(start 0.67945 -0.305054)
			(end 0.12065 -0.305054)
			(stroke
				(width 0.1)
				(type default)
			)
			(layer "B.Fab")
		)
		(fp_line
			(start 0.12065 -0.305054)
			(end 0.12065 -0.2794)
			(stroke
				(width 0.1)
				(type default)
			)
			(layer "B.Fab")
		)
		(fp_line
			(start -0.12065 -0.3048)
			(end -0.67945 -0.3048)
			(stroke
				(width 0.1)
				(type default)
			)
			(layer "B.Fab")
		)
		(fp_line
			(start -0.67945 -0.3048)
			(end -0.67945 0.3048)
			(stroke
				(width 0.1)
				(type default)
			)
			(layer "B.Fab")
		)
		(fp_line
			(start 0.12065 -0.2794)
			(end -0.12065 -0.2794)
			(stroke
				(width 0.1)
				(type default)
			)
			(layer "B.Fab")
		)
		(fp_line
			(start -0.12065 -0.2794)
			(end -0.12065 -0.3048)
			(stroke
				(width 0.1)
				(type default)
			)
			(layer "B.Fab")
		)
		(fp_line
			(start 0.12065 0.2794)
			(end 0.12065 0.3048)
			(stroke
				(width 0.1)
				(type default)
			)
			(layer "B.Fab")
		)
		(fp_line
			(start -0.120396 0.2794)
			(end 0.12065 0.2794)
			(stroke
				(width 0.1)
				(type default)
			)
			(layer "B.Fab")
		)
		(fp_line
			(start 0.67945 0.3048)
			(end 0.67945 -0.305054)
			(stroke
				(width 0.1)
				(type default)
			)
			(layer "B.Fab")
		)
		(fp_line
			(start 0.12065 0.3048)
			(end 0.67945 0.3048)
			(stroke
				(width 0.1)
				(type default)
			)
			(layer "B.Fab")
		)
		(fp_line
			(start -0.120396 0.3048)
			(end -0.120396 0.2794)
			(stroke
				(width 0.1)
				(type default)
			)
			(layer "B.Fab")
		)
		(fp_line
			(start -0.67945 0.3048)
			(end -0.120396 0.3048)
			(stroke
				(width 0.1)
				(type default)
			)
			(layer "B.Fab")
		)
		(pad "1" smd circle
			(at 0.40005 0 270)
			(size 0 0)
			(layers "B.Cu" "B.Mask" "B.Paste")
			(net "PWRGD_CHC_CPU1_DIMM2")
		)
		(pad "2" smd circle
			(at -0.40005 0 270)
			(size 0 0)
			(layers "B.Cu" "B.Mask" "B.Paste")
			(net "PWRGD_FAIL_CPU1_CD")
		)
	)
	(footprint ""
		(layer "B.Cu")
		(at 61.62421 -165.11397)
		(property "Reference" "PC1940"
			(at 0 0 0)
			(layer "B.SilkS")
			(hide yes)
			(effects
				(font
					(size 1.27 1.27)
				)
				(justify mirror)
			)
		)
		(property "Value" ""
			(at 0 0 0)
			(layer "B.Fab")
			(effects
				(font
					(size 1.27 1.27)
				)
				(justify mirror)
			)
		)
		(duplicate_pad_numbers_are_jumpers no)
		(fp_line
			(start -4.53898 -2.15011)
			(end -4.53898 2.15011)
			(stroke
				(width 0.1524)
				(type default)
			)
			(layer "B.SilkS")
		)
		(fp_line
			(start -4.53898 2.15011)
			(end 4.53898 2.15011)
			(stroke
				(width 0.1524)
				(type default)
			)
			(layer "B.SilkS")
		)
		(fp_line
			(start 4.53898 -2.150618)
			(end 4.539742 2.152142)
			(stroke
				(width 0.1524)
				(type default)
			)
			(layer "B.SilkS")
		)
		(fp_line
			(start 4.53898 -2.15011)
			(end -4.53898 -2.15011)
			(stroke
				(width 0.1524)
				(type default)
			)
			(layer "B.SilkS")
		)
		(fp_line
			(start 4.53898 2.15011)
			(end 4.53898 -2.15011)
			(stroke
				(width 0.1524)
				(type default)
			)
			(layer "B.SilkS")
		)
		(fp_line
			(start 4.69138 -2.150618)
			(end 4.692396 2.161032)
			(stroke
				(width 0.1524)
				(type default)
			)
			(layer "B.SilkS")
		)
		(fp_line
			(start 4.83108 2.150364)
			(end 4.447794 2.149348)
			(stroke
				(width 0.1524)
				(type default)
			)
			(layer "B.SilkS")
		)
		(fp_line
			(start 4.84378 -2.150618)
			(end 4.53898 -2.150618)
			(stroke
				(width 0.1524)
				(type default)
			)
			(layer "B.SilkS")
		)
		(fp_line
			(start 4.84378 -2.150618)
			(end 4.842256 2.163064)
			(stroke
				(width 0.1524)
				(type default)
			)
			(layer "B.SilkS")
		)
		(fp_line
			(start -3.64998 -2.15011)
			(end -3.64998 2.15011)
			(stroke
				(width 0.1)
				(type default)
			)
			(layer "B.Fab")
		)
		(fp_line
			(start -3.64998 2.15011)
			(end 3.64998 2.15011)
			(stroke
				(width 0.1)
				(type default)
			)
			(layer "B.Fab")
		)
		(fp_line
			(start 3.64998 -2.15011)
			(end -3.64998 -2.15011)
			(stroke
				(width 0.1)
				(type default)
			)
			(layer "B.Fab")
		)
		(fp_line
			(start 3.64998 2.15011)
			(end 3.64998 -2.15011)
			(stroke
				(width 0.1)
				(type default)
			)
			(layer "B.Fab")
		)
		(fp_text user "-"
			(at -4.94157 0.951992 0)
			(unlocked yes)
			(layer "B.SilkS")
			(effects
				(font
					(size 1.905 1.4224)
					(thickness 0.1524)
				)
				(justify left mirror)
			)
		)
		(fp_text user "+"
			(at 6.214872 -0.337058 0)
			(unlocked yes)
			(layer "B.SilkS")
			(effects
				(font
					(size 1.905 1.4224)
					(thickness 0.1524)
				)
				(justify left mirror)
			)
		)
		(fp_text user "-"
			(at -4.313174 -0.094488 0)
			(unlocked yes)
			(layer "B.Fab")
			(effects
				(font
					(size 1.905 1.4224)
					(thickness 0.1524)
				)
				(justify left mirror)
			)
		)
		(fp_text user "+"
			(at 6.214872 -0.337058 0)
			(unlocked yes)
			(layer "B.Fab")
			(effects
				(font
					(size 1.905 1.4224)
					(thickness 0.1524)
				)
				(justify left mirror)
			)
		)
		(pad "1" smd rect
			(at 3.199892 0 180)
			(size 2.413 2.8194)
			(layers "B.Cu" "B.Mask" "B.Paste")
			(net "PVCCD_HV_CPU1")
		)
		(pad "2" smd rect
			(at -3.199892 0 180)
			(size 2.413 2.8194)
			(layers "B.Cu" "B.Mask" "B.Paste")
			(net "GND")
		)
	)
)
